# S9S_MB_2U (Grand Teton) — schematic netlist excerpt (pin names and nets, part order shuffled) for the footprints in the layout excerpt that follows; sources: Cadence DE-HDL packaged netlist, KiCad conversion of 03242023_DA0F0TMBIJ0_F0T_Motherboard_J_brd_V01_OCP.brd

C539  Q_CAP  0.1UF 25V 10% X7R  pkg 0402  page 133 : A = P3V3_AUX ; B = GND
C2336  Q_CAP  0.1UF 25V 10% X7R  pkg 0402  page 211 : A = P3V3_9ZXL045_VDD ; B = GND

(kicad_pcb
	(version 20260206)
	(generator "pcbnew")
	(generator_version "10.0")
	(general
		(thickness 1.6)
		(legacy_teardrops no)
	)
	(paper "A4")
	(title_block
		(title "03242023_DA0F0TMBIJ0_F0T_Motherboard_J_brd_V01_OCP.brd")
		(comment 1 "Grand Teton / footprints 5601-5602 of 6105")
	)
	(layers
		(0 "F.Cu" signal "TOP")
		(4 "In1.Cu" signal "GND")
		(6 "In2.Cu" signal "IN1")
		(8 "In3.Cu" signal "GND1")
		(10 "In4.Cu" signal "IN2")
		(12 "In5.Cu" signal "GND2")
		(14 "In6.Cu" signal "IN3")
		(16 "In7.Cu" signal "GND3")
		(18 "In8.Cu" signal "VCC")
		(20 "In9.Cu" signal "VCC1")
		(22 "In10.Cu" signal "GND4")
		(24 "In11.Cu" signal "IN4")
		(26 "In12.Cu" signal "GND5")
		(28 "In13.Cu" signal "IN5")
		(30 "In14.Cu" signal "GND6")
		(32 "In15.Cu" signal "IN6")
		(34 "In16.Cu" signal "GND7")
		(2 "B.Cu" signal "BOTTOM")
		(9 "F.Adhes" user "F.Adhesive")
		(11 "B.Adhes" user "B.Adhesive")
		(13 "F.Paste" user "Package Geometry/Pastemask Top")
		(15 "B.Paste" user "Package Geometry/Pastemask Bottom")
		(5 "F.SilkS" user "Ref Des/Silkscreen Top")
		(7 "B.SilkS" user "Ref Des/Silkscreen Bottom")
		(1 "F.Mask" user "Board Geometry/Soldermask Top")
		(3 "B.Mask" user "Board Geometry/Soldermask Bottom")
		(17 "Dwgs.User" user "User.Drawings")
		(19 "Cmts.User" user "User.Comments")
		(21 "Eco1.User" user "User.Eco1")
		(23 "Eco2.User" user "User.Eco2")
		(25 "Edge.Cuts" user "Board Geometry/Outline")
		(27 "Margin" user)
		(31 "F.CrtYd" user "Package Geometry/Place Bound Top")
		(29 "B.CrtYd" user "Package Geometry/Place Bound Bottom")
		(35 "F.Fab" user "Ref Des/Assembly Top")
		(33 "B.Fab" user "Ref Des/Assembly Bottom")
	)
	(footprint ""
		(layer "B.Cu")
		(at 204.133958 -194.03441)
		(property "Reference" "C539"
			(at 0 0 0)
			(layer "B.SilkS")
			(hide yes)
			(effects
				(font
					(size 1.27 1.27)
				)
				(justify mirror)
			)
		)
		(property "Value" ""
			(at 0 0 0)
			(layer "B.Fab")
			(effects
				(font
					(size 1.27 1.27)
				)
				(justify mirror)
			)
		)
		(duplicate_pad_numbers_are_jumpers no)
		(fp_line
			(start -0.7874 -0.4064)
			(end -0.7874 0.4064)
			(stroke
				(width 0.1524)
				(type default)
			)
			(layer "B.SilkS")
		)
		(fp_line
			(start -0.7874 0.4064)
			(end 0.7874 0.4064)
			(stroke
				(width 0.1524)
				(type default)
			)
			(layer "B.SilkS")
		)
		(fp_line
			(start 0.7874 -0.4064)
			(end -0.7874 -0.4064)
			(stroke
				(width 0.1524)
				(type default)
			)
			(layer "B.SilkS")
		)
		(fp_line
			(start 0.7874 0.4064)
			(end 0.7874 -0.4064)
			(stroke
				(width 0.1524)
				(type default)
			)
			(layer "B.SilkS")
		)
		(fp_line
			(start -0.67945 -0.3048)
			(end -0.67945 0.3048)
			(stroke
				(width 0.1)
				(type default)
			)
			(layer "B.Fab")
		)
		(fp_line
			(start -0.67945 0.3048)
			(end -0.120396 0.3048)
			(stroke
				(width 0.1)
				(type default)
			)
			(layer "B.Fab")
		)
		(fp_line
			(start -0.12065 -0.3048)
			(end -0.67945 -0.3048)
			(stroke
				(width 0.1)
				(type default)
			)
			(layer "B.Fab")
		)
		(fp_line
			(start -0.12065 -0.2794)
			(end -0.12065 -0.3048)
			(stroke
				(width 0.1)
				(type default)
			)
			(layer "B.Fab")
		)
		(fp_line
			(start -0.120396 0.2794)
			(end 0.12065 0.2794)
			(stroke
				(width 0.1)
				(type default)
			)
			(layer "B.Fab")
		)
		(fp_line
			(start -0.120396 0.3048)
			(end -0.120396 0.2794)
			(stroke
				(width 0.1)
				(type default)
			)
			(layer "B.Fab")
		)
		(fp_line
			(start 0.12065 -0.305054)
			(end 0.12065 -0.2794)
			(stroke
				(width 0.1)
				(type default)
			)
			(layer "B.Fab")
		)
		(fp_line
			(start 0.12065 -0.2794)
			(end -0.12065 -0.2794)
			(stroke
				(width 0.1)
				(type default)
			)
			(layer "B.Fab")
		)
		(fp_line
			(start 0.12065 0.2794)
			(end 0.12065 0.3048)
			(stroke
				(width 0.1)
				(type default)
			)
			(layer "B.Fab")
		)
		(fp_line
			(start 0.12065 0.3048)
			(end 0.67945 0.3048)
			(stroke
				(width 0.1)
				(type default)
			)
			(layer "B.Fab")
		)
		(fp_line
			(start 0.67945 -0.305054)
			(end 0.12065 -0.305054)
			(stroke
				(width 0.1)
				(type default)
			)
			(layer "B.Fab")
		)
		(fp_line
			(start 0.67945 0.3048)
			(end 0.67945 -0.305054)
			(stroke
				(width 0.1)
				(type default)
			)
			(layer "B.Fab")
		)
		(pad "1" smd circle
			(at 0.40005 0 180)
			(size 0 0)
			(layers "B.Cu" "B.Mask" "B.Paste")
			(net "P3V3_AUX")
		)
		(pad "2" smd circle
			(at -0.40005 0 180)
			(size 0 0)
			(layers "B.Cu" "B.Mask" "B.Paste")
			(net "GND")
		)
	)
	(footprint ""
		(layer "B.Cu")
		(at 109.944154 -411.438598 -90)
		(property "Reference" "C2336"
			(at 0 0 90)
			(layer "B.SilkS")
			(hide yes)
			(effects
				(font
					(size 1.27 1.27)
				)
				(justify mirror)
			)
		)
		(property "Value" ""
			(at 0 0 90)
			(layer "B.Fab")
			(effects
				(font
					(size 1.27 1.27)
				)
				(justify mirror)
			)
		)
		(duplicate_pad_numbers_are_jumpers no)
		(fp_line
			(start -0.7874 0.4064)
			(end 0.7874 0.4064)
			(stroke
				(width 0.1524)
				(type default)
			)
			(layer "B.SilkS")
		)
		(fp_line
			(start 0.7874 0.4064)
			(end 0.7874 -0.4064)
			(stroke
				(width 0.1524)
				(type default)
			)
			(layer "B.SilkS")
		)
		(fp_line
			(start -0.7874 -0.4064)
			(end -0.7874 0.4064)
			(stroke
				(width 0.1524)
				(type default)
			)
			(layer "B.SilkS")
		)
		(fp_line
			(start 0.7874 -0.4064)
			(end -0.7874 -0.4064)
			(stroke
				(width 0.1524)
				(type default)
			)
			(layer "B.SilkS")
		)
		(fp_line
			(start -0.67945 0.3048)
			(end -0.120396 0.3048)
			(stroke
				(width 0.1)
				(type default)
			)
			(layer "B.Fab")
		)
		(fp_line
			(start -0.120396 0.3048)
			(end -0.120396 0.2794)
			(stroke
				(width 0.1)
				(type default)
			)
			(layer "B.Fab")
		)
		(fp_line
			(start 0.12065 0.3048)
			(end 0.67945 0.3048)
			(stroke
				(width 0.1)
				(type default)
			)
			(layer "B.Fab")
		)
		(fp_line
			(start 0.67945 0.3048)
			(end 0.67945 -0.305054)
			(stroke
				(width 0.1)
				(type default)
			)
			(layer "B.Fab")
		)
		(fp_line
			(start -0.120396 0.2794)
			(end 0.12065 0.2794)
			(stroke
				(width 0.1)
				(type default)
			)
			(layer "B.Fab")
		)
		(fp_line
			(start 0.12065 0.2794)
			(end 0.12065 0.3048)
			(stroke
				(width 0.1)
				(type default)
			)
			(layer "B.Fab")
		)
		(fp_line
			(start -0.12065 -0.2794)
			(end -0.12065 -0.3048)
			(stroke
				(width 0.1)
				(type default)
			)
			(layer "B.Fab")
		)
		(fp_line
			(start 0.12065 -0.2794)
			(end -0.12065 -0.2794)
			(stroke
				(width 0.1)
				(type default)
			)
			(layer "B.Fab")
		)
		(fp_line
			(start -0.67945 -0.3048)
			(end -0.67945 0.3048)
			(stroke
				(width 0.1)
				(type default)
			)
			(layer "B.Fab")
		)
		(fp_line
			(start -0.12065 -0.3048)
			(end -0.67945 -0.3048)
			(stroke
				(width 0.1)
				(type default)
			)
			(layer "B.Fab")
		)
		(fp_line
			(start 0.12065 -0.305054)
			(end 0.12065 -0.2794)
			(stroke
				(width 0.1)
				(type default)
			)
			(layer "B.Fab")
		)
		(fp_line
			(start 0.67945 -0.305054)
			(end 0.12065 -0.305054)
			(stroke
				(width 0.1)
				(type default)
			)
			(layer "B.Fab")
		)
		(pad "1" smd circle
			(at 0.40005 0 90)
			(size 0 0)
			(layers "B.Cu" "B.Mask" "B.Paste")
			(net "P3V3_9ZXL045_VDD")
		)
		(pad "2" smd circle
			(at -0.40005 0 90)
			(size 0 0)
			(layers "B.Cu" "B.Mask" "B.Paste")
			(net "GND")
		)
	)
)
